# T6G (Grand Teton) — schematic netlist excerpt (pin names and nets, part order shuffled) for the footprints in the layout excerpt that follows; sources: Cadence DE-HDL packaged netlist, KiCad conversion of 04192023_DAF0TMB3IC0_F0TG_MB_C_brd_V02_OCP.brd

C10  Q_CAP  0.1UF 25V 10% X7R  pkg 0402  page 133 : A = P3V3_AUX ; B = GND
PR3805  Q_RES  160K 1% CHIP  pkg 0402LF  page 140 : A = P12V_AUX ; B = P12V_OCP_UV_2
C6567  Q_CAP_DIFFBUS  DIFF BUS_0.22UF 6.3V 20% X6S  pkg C0201  page 297 : \1\ = P5E_CPU0_P2_TX_BUF_C_DP<1> ; \2\ = P5E_CPU0_P2_TX_BUF_DP<1>

(kicad_pcb
	(version 20260206)
	(generator "pcbnew")
	(generator_version "10.0")
	(general
		(thickness 1.6)
		(legacy_teardrops no)
	)
	(paper "A4")
	(title_block
		(title "04192023_DAF0TMB3IC0_F0TG_MB_C_brd_V02_OCP.brd")
		(comment 1 "Grand Teton / footprints 2954-2956 of 8354")
	)
	(layers
		(0 "F.Cu" signal "TOP")
		(4 "In1.Cu" signal "GND")
		(6 "In2.Cu" signal "IN1")
		(8 "In3.Cu" signal "GND1")
		(10 "In4.Cu" signal "IN2")
		(12 "In5.Cu" signal "GND2")
		(14 "In6.Cu" signal "IN3")
		(16 "In7.Cu" signal "GND3")
		(18 "In8.Cu" signal "VCC")
		(20 "In9.Cu" signal "VCC1")
		(22 "In10.Cu" signal "GND4")
		(24 "In11.Cu" signal "IN4")
		(26 "In12.Cu" signal "GND5")
		(28 "In13.Cu" signal "IN5")
		(30 "In14.Cu" signal "GND6")
		(32 "In15.Cu" signal "IN6")
		(34 "In16.Cu" signal "GND7")
		(2 "B.Cu" signal "BOTTOM")
		(9 "F.Adhes" user "F.Adhesive")
		(11 "B.Adhes" user "B.Adhesive")
		(13 "F.Paste" user "Package Geometry/Pastemask Top")
		(15 "B.Paste" user "Package Geometry/Pastemask Bottom")
		(5 "F.SilkS" user "Ref Des/Silkscreen Top")
		(7 "B.SilkS" user "Ref Des/Silkscreen Bottom")
		(1 "F.Mask" user "Board Geometry/Soldermask Top")
		(3 "B.Mask" user "Board Geometry/Soldermask Bottom")
		(17 "Dwgs.User" user "User.Drawings")
		(19 "Cmts.User" user "User.Comments")
		(21 "Eco1.User" user "User.Eco1")
		(23 "Eco2.User" user "User.Eco2")
		(25 "Edge.Cuts" user "Board Geometry/Outline")
		(27 "Margin" user)
		(31 "F.CrtYd" user "Package Geometry/Place Bound Top")
		(29 "B.CrtYd" user "Package Geometry/Place Bound Bottom")
		(35 "F.Fab" user "Ref Des/Assembly Top")
		(33 "B.Fab" user "Ref Des/Assembly Bottom")
	)
	(footprint ""
		(layer "F.Cu")
		(at 76.115164 -18.066512)
		(property "Reference" "PR3805"
			(at 0 0 0)
			(layer "F.SilkS")
			(hide yes)
			(effects
				(font
					(size 1.27 1.27)
				)
			)
		)
		(property "Value" ""
			(at 0 0 0)
			(layer "F.Fab")
			(effects
				(font
					(size 1.27 1.27)
				)
			)
		)
		(duplicate_pad_numbers_are_jumpers no)
		(fp_line
			(start -0.7874 -0.4064)
			(end 0.7874 -0.4064)
			(stroke
				(width 0.1524)
				(type default)
			)
			(layer "F.SilkS")
		)
		(fp_line
			(start -0.7874 0.4064)
			(end -0.7874 -0.4064)
			(stroke
				(width 0.1524)
				(type default)
			)
			(layer "F.SilkS")
		)
		(fp_line
			(start 0.7874 -0.4064)
			(end 0.7874 0.4064)
			(stroke
				(width 0.1524)
				(type default)
			)
			(layer "F.SilkS")
		)
		(fp_line
			(start 0.7874 0.4064)
			(end -0.7874 0.4064)
			(stroke
				(width 0.1524)
				(type default)
			)
			(layer "F.SilkS")
		)
		(fp_line
			(start -0.67945 -0.305054)
			(end -0.12065 -0.305054)
			(stroke
				(width 0.1)
				(type default)
			)
			(layer "F.Fab")
		)
		(fp_line
			(start -0.67945 0.3048)
			(end -0.67945 -0.305054)
			(stroke
				(width 0.1)
				(type default)
			)
			(layer "F.Fab")
		)
		(fp_line
			(start -0.12065 -0.305054)
			(end -0.12065 -0.2794)
			(stroke
				(width 0.1)
				(type default)
			)
			(layer "F.Fab")
		)
		(fp_line
			(start -0.12065 -0.2794)
			(end 0.12065 -0.2794)
			(stroke
				(width 0.1)
				(type default)
			)
			(layer "F.Fab")
		)
		(fp_line
			(start -0.12065 0.2794)
			(end -0.12065 0.3048)
			(stroke
				(width 0.1)
				(type default)
			)
			(layer "F.Fab")
		)
		(fp_line
			(start -0.12065 0.3048)
			(end -0.67945 0.3048)
			(stroke
				(width 0.1)
				(type default)
			)
			(layer "F.Fab")
		)
		(fp_line
			(start 0.120396 0.2794)
			(end -0.12065 0.2794)
			(stroke
				(width 0.1)
				(type default)
			)
			(layer "F.Fab")
		)
		(fp_line
			(start 0.120396 0.3048)
			(end 0.120396 0.2794)
			(stroke
				(width 0.1)
				(type default)
			)
			(layer "F.Fab")
		)
		(fp_line
			(start 0.12065 -0.3048)
			(end 0.67945 -0.3048)
			(stroke
				(width 0.1)
				(type default)
			)
			(layer "F.Fab")
		)
		(fp_line
			(start 0.12065 -0.2794)
			(end 0.12065 -0.3048)
			(stroke
				(width 0.1)
				(type default)
			)
			(layer "F.Fab")
		)
		(fp_line
			(start 0.67945 -0.3048)
			(end 0.67945 0.3048)
			(stroke
				(width 0.1)
				(type default)
			)
			(layer "F.Fab")
		)
		(fp_line
			(start 0.67945 0.3048)
			(end 0.120396 0.3048)
			(stroke
				(width 0.1)
				(type default)
			)
			(layer "F.Fab")
		)
		(pad "1" smd circle
			(at -0.40005 0)
			(size 0 0)
			(layers "F.Cu" "F.Mask" "F.Paste")
			(net "P12V_AUX")
		)
		(pad "2" smd circle
			(at 0.40005 0)
			(size 0 0)
			(layers "F.Cu" "F.Mask" "F.Paste")
			(net "P12V_OCP_UV_2")
		)
	)
	(footprint ""
		(layer "F.Cu")
		(at 374.846342 -416.899344 -90)
		(property "Reference" "C6567"
			(at 0 0 270)
			(layer "F.SilkS")
			(hide yes)
			(effects
				(font
					(size 1.27 1.27)
				)
			)
		)
		(property "Value" ""
			(at 0 0 270)
			(layer "F.Fab")
			(effects
				(font
					(size 1.27 1.27)
				)
			)
		)
		(duplicate_pad_numbers_are_jumpers no)
		(fp_line
			(start -0.299974 0.150114)
			(end -0.299974 -0.150114)
			(stroke
				(width 0.1)
				(type default)
			)
			(layer "F.Fab")
		)
		(fp_line
			(start 0.299974 0.150114)
			(end -0.299974 0.150114)
			(stroke
				(width 0.1)
				(type default)
			)
			(layer "F.Fab")
		)
		(fp_line
			(start -0.299974 -0.150114)
			(end 0.299974 -0.150114)
			(stroke
				(width 0.1)
				(type default)
			)
			(layer "F.Fab")
		)
		(fp_line
			(start 0.299974 -0.150114)
			(end 0.299974 0.150114)
			(stroke
				(width 0.1)
				(type default)
			)
			(layer "F.Fab")
		)
		(pad "1" smd rect
			(at -0.2667 0 270)
			(size 0.3048 0.381)
			(layers "F.Cu" "F.Mask" "F.Paste")
			(net "P5E_CPU0_P2_TX_BUF_C_DP<1>")
		)
		(pad "2" smd rect
			(at 0.2667 0 270)
			(size 0.3048 0.381)
			(layers "F.Cu" "F.Mask" "F.Paste")
			(net "P5E_CPU0_P2_TX_BUF_DP<1>")
		)
	)
	(footprint ""
		(layer "F.Cu")
		(at 210.608672 -126.469648)
		(property "Reference" "C10"
			(at 0 0 0)
			(layer "F.SilkS")
			(hide yes)
			(effects
				(font
					(size 1.27 1.27)
				)
			)
		)
		(property "Value" ""
			(at 0 0 0)
			(layer "F.Fab")
			(effects
				(font
					(size 1.27 1.27)
				)
			)
		)
		(duplicate_pad_numbers_are_jumpers no)
		(fp_line
			(start -0.7874 -0.4064)
			(end 0.7874 -0.4064)
			(stroke
				(width 0.1524)
				(type default)
			)
			(layer "F.SilkS")
		)
		(fp_line
			(start -0.7874 0.4064)
			(end -0.7874 -0.4064)
			(stroke
				(width 0.1524)
				(type default)
			)
			(layer "F.SilkS")
		)
		(fp_line
			(start 0.7874 -0.4064)
			(end 0.7874 0.4064)
			(stroke
				(width 0.1524)
				(type default)
			)
			(layer "F.SilkS")
		)
		(fp_line
			(start 0.7874 0.4064)
			(end -0.7874 0.4064)
			(stroke
				(width 0.1524)
				(type default)
			)
			(layer "F.SilkS")
		)
		(fp_line
			(start -0.67945 -0.305054)
			(end -0.12065 -0.305054)
			(stroke
				(width 0.1)
				(type default)
			)
			(layer "F.Fab")
		)
		(fp_line
			(start -0.67945 0.3048)
			(end -0.67945 -0.305054)
			(stroke
				(width 0.1)
				(type default)
			)
			(layer "F.Fab")
		)
		(fp_line
			(start -0.12065 -0.305054)
			(end -0.12065 -0.2794)
			(stroke
				(width 0.1)
				(type default)
			)
			(layer "F.Fab")
		)
		(fp_line
			(start -0.12065 -0.2794)
			(end 0.12065 -0.2794)
			(stroke
				(width 0.1)
				(type default)
			)
			(layer "F.Fab")
		)
		(fp_line
			(start -0.12065 0.2794)
			(end -0.12065 0.3048)
			(stroke
				(width 0.1)
				(type default)
			)
			(layer "F.Fab")
		)
		(fp_line
			(start -0.12065 0.3048)
			(end -0.67945 0.3048)
			(stroke
				(width 0.1)
				(type default)
			)
			(layer "F.Fab")
		)
		(fp_line
			(start 0.120396 0.2794)
			(end -0.12065 0.2794)
			(stroke
				(width 0.1)
				(type default)
			)
			(layer "F.Fab")
		)
		(fp_line
			(start 0.120396 0.3048)
			(end 0.120396 0.2794)
			(stroke
				(width 0.1)
				(type default)
			)
			(layer "F.Fab")
		)
		(fp_line
			(start 0.12065 -0.3048)
			(end 0.67945 -0.3048)
			(stroke
				(width 0.1)
				(type default)
			)
			(layer "F.Fab")
		)
		(fp_line
			(start 0.12065 -0.2794)
			(end 0.12065 -0.3048)
			(stroke
				(width 0.1)
				(type default)
			)
			(layer "F.Fab")
		)
		(fp_line
			(start 0.67945 -0.3048)
			(end 0.67945 0.3048)
			(stroke
				(width 0.1)
				(type default)
			)
			(layer "F.Fab")
		)
		(fp_line
			(start 0.67945 0.3048)
			(end 0.120396 0.3048)
			(stroke
				(width 0.1)
				(type default)
			)
			(layer "F.Fab")
		)
		(pad "1" smd circle
			(at -0.40005 0)
			(size 0 0)
			(layers "F.Cu" "F.Mask" "F.Paste")
			(net "P3V3_AUX")
		)
		(pad "2" smd circle
			(at 0.40005 0)
			(size 0 0)
			(layers "F.Cu" "F.Mask" "F.Paste")
			(net "GND")
		)
	)
)
